(kicad_pcb
	(version 20260206)
	(generator "pcbnew")
	(generator_version "10.0")
	(general
		(thickness 1.6)
		(legacy_teardrops no)
	)
	(paper "A4")
	(title_block
		(title "03242023_DA0F0TMBIJ0_F0T_Motherboard_J_brd_V01_OCP.brd")
		(comment 1 "Grand Teton / footprints 3338-3343 of 6105")
	)
	(layers
		(0 "F.Cu" signal "TOP")
		(4 "In1.Cu" signal "GND")
		(6 "In2.Cu" signal "IN1")
		(8 "In3.Cu" signal "GND1")
		(10 "In4.Cu" signal "IN2")
		(12 "In5.Cu" signal "GND2")
		(14 "In6.Cu" signal "IN3")
		(16 "In7.Cu" signal "GND3")
		(18 "In8.Cu" signal "VCC")
		(20 "In9.Cu" signal "VCC1")
		(22 "In10.Cu" signal "GND4")
		(24 "In11.Cu" signal "IN4")
		(26 "In12.Cu" signal "GND5")
		(28 "In13.Cu" signal "IN5")
		(30 "In14.Cu" signal "GND6")
		(32 "In15.Cu" signal "IN6")
		(34 "In16.Cu" signal "GND7")
		(2 "B.Cu" signal "BOTTOM")
		(9 "F.Adhes" user "F.Adhesive")
		(11 "B.Adhes" user "B.Adhesive")
		(13 "F.Paste" user "Package Geometry/Pastemask Top")
		(15 "B.Paste" user "Package Geometry/Pastemask Bottom")
		(5 "F.SilkS" user "Ref Des/Silkscreen Top")
		(7 "B.SilkS" user "Ref Des/Silkscreen Bottom")
		(1 "F.Mask" user "Board Geometry/Soldermask Top")
		(3 "B.Mask" user "Board Geometry/Soldermask Bottom")
		(17 "Dwgs.User" user "User.Drawings")
		(19 "Cmts.User" user "User.Comments")
		(21 "Eco1.User" user "User.Eco1")
		(23 "Eco2.User" user "User.Eco2")
		(25 "Edge.Cuts" user "Board Geometry/Outline")
		(27 "Margin" user)
		(31 "F.CrtYd" user "Package Geometry/Place Bound Top")
		(29 "B.CrtYd" user "Package Geometry/Place Bound Bottom")
		(35 "F.Fab" user "Ref Des/Assembly Top")
		(33 "B.Fab" user "Ref Des/Assembly Bottom")
	)
	(footprint ""
		(layer "F.Cu")
		(at 180.01488 -97.119948 -90)
		(property "Reference" "R4293"
			(at 0 0 270)
			(layer "F.SilkS")
			(hide yes)
			(effects
				(font
					(size 1.27 1.27)
				)
			)
		)
		(property "Value" ""
			(at 0 0 270)
			(layer "F.Fab")
			(effects
				(font
					(size 1.27 1.27)
				)
			)
		)
		(duplicate_pad_numbers_are_jumpers no)
		(fp_line
			(start -0.7874 0.4064)
			(end -0.7874 -0.4064)
			(stroke
				(width 0.1524)
				(type default)
			)
			(layer "F.SilkS")
		)
		(fp_line
			(start 0.7874 0.4064)
			(end -0.7874 0.4064)
			(stroke
				(width 0.1524)
				(type default)
			)
			(layer "F.SilkS")
		)
		(fp_line
			(start -0.7874 -0.4064)
			(end 0.7874 -0.4064)
			(stroke
				(width 0.1524)
				(type default)
			)
			(layer "F.SilkS")
		)
		(fp_line
			(start 0.7874 -0.4064)
			(end 0.7874 0.4064)
			(stroke
				(width 0.1524)
				(type default)
			)
			(layer "F.SilkS")
		)
		(fp_line
			(start -0.67945 0.3048)
			(end -0.67945 -0.305054)
			(stroke
				(width 0.1)
				(type default)
			)
			(layer "F.Fab")
		)
		(fp_line
			(start -0.12065 0.3048)
			(end -0.67945 0.3048)
			(stroke
				(width 0.1)
				(type default)
			)
			(layer "F.Fab")
		)
		(fp_line
			(start 0.120396 0.3048)
			(end 0.120396 0.2794)
			(stroke
				(width 0.1)
				(type default)
			)
			(layer "F.Fab")
		)
		(fp_line
			(start 0.67945 0.3048)
			(end 0.120396 0.3048)
			(stroke
				(width 0.1)
				(type default)
			)
			(layer "F.Fab")
		)
		(fp_line
			(start -0.12065 0.2794)
			(end -0.12065 0.3048)
			(stroke
				(width 0.1)
				(type default)
			)
			(layer "F.Fab")
		)
		(fp_line
			(start 0.120396 0.2794)
			(end -0.12065 0.2794)
			(stroke
				(width 0.1)
				(type default)
			)
			(layer "F.Fab")
		)
		(fp_line
			(start -0.12065 -0.2794)
			(end 0.12065 -0.2794)
			(stroke
				(width 0.1)
				(type default)
			)
			(layer "F.Fab")
		)
		(fp_line
			(start 0.12065 -0.2794)
			(end 0.12065 -0.3048)
			(stroke
				(width 0.1)
				(type default)
			)
			(layer "F.Fab")
		)
		(fp_line
			(start 0.12065 -0.3048)
			(end 0.67945 -0.3048)
			(stroke
				(width 0.1)
				(type default)
			)
			(layer "F.Fab")
		)
		(fp_line
			(start 0.67945 -0.3048)
			(end 0.67945 0.3048)
			(stroke
				(width 0.1)
				(type default)
			)
			(layer "F.Fab")
		)
		(fp_line
			(start -0.67945 -0.305054)
			(end -0.12065 -0.305054)
			(stroke
				(width 0.1)
				(type default)
			)
			(layer "F.Fab")
		)
		(fp_line
			(start -0.12065 -0.305054)
			(end -0.12065 -0.2794)
			(stroke
				(width 0.1)
				(type default)
			)
			(layer "F.Fab")
		)
		(pad "1" smd circle
			(at -0.40005 0 270)
			(size 0 0)
			(layers "F.Cu" "F.Mask" "F.Paste")
			(net "H_CPU0_MEMHOT_IN_LVC1_R1_N")
		)
		(pad "2" smd circle
			(at 0.40005 0 270)
			(size 0 0)
			(layers "F.Cu" "F.Mask" "F.Paste")
			(net "H_CPU0_MEMHOT_IN_LVC1_N")
		)
	)
	(footprint ""
		(layer "F.Cu")
		(at 211.102956 -30.276292 90)
		(property "Reference" "R3613"
			(at 0 0 90)
			(layer "F.SilkS")
			(hide yes)
			(effects
				(font
					(size 1.27 1.27)
				)
			)
		)
		(property "Value" ""
			(at 0 0 90)
			(layer "F.Fab")
			(effects
				(font
					(size 1.27 1.27)
				)
			)
		)
		(duplicate_pad_numbers_are_jumpers no)
		(fp_line
			(start 0.7874 -0.4064)
			(end 0.7874 0.4064)
			(stroke
				(width 0.1524)
				(type default)
			)
			(layer "F.SilkS")
		)
		(fp_line
			(start -0.7874 -0.4064)
			(end 0.7874 -0.4064)
			(stroke
				(width 0.1524)
				(type default)
			)
			(layer "F.SilkS")
		)
		(fp_line
			(start 0.7874 0.4064)
			(end -0.7874 0.4064)
			(stroke
				(width 0.1524)
				(type default)
			)
			(layer "F.SilkS")
		)
		(fp_line
			(start -0.7874 0.4064)
			(end -0.7874 -0.4064)
			(stroke
				(width 0.1524)
				(type default)
			)
			(layer "F.SilkS")
		)
		(fp_line
			(start -0.12065 -0.305054)
			(end -0.12065 -0.2794)
			(stroke
				(width 0.1)
				(type default)
			)
			(layer "F.Fab")
		)
		(fp_line
			(start -0.67945 -0.305054)
			(end -0.12065 -0.305054)
			(stroke
				(width 0.1)
				(type default)
			)
			(layer "F.Fab")
		)
		(fp_line
			(start 0.67945 -0.3048)
			(end 0.67945 0.3048)
			(stroke
				(width 0.1)
				(type default)
			)
			(layer "F.Fab")
		)
		(fp_line
			(start 0.12065 -0.3048)
			(end 0.67945 -0.3048)
			(stroke
				(width 0.1)
				(type default)
			)
			(layer "F.Fab")
		)
		(fp_line
			(start 0.12065 -0.2794)
			(end 0.12065 -0.3048)
			(stroke
				(width 0.1)
				(type default)
			)
			(layer "F.Fab")
		)
		(fp_line
			(start -0.12065 -0.2794)
			(end 0.12065 -0.2794)
			(stroke
				(width 0.1)
				(type default)
			)
			(layer "F.Fab")
		)
		(fp_line
			(start 0.120396 0.2794)
			(end -0.12065 0.2794)
			(stroke
				(width 0.1)
				(type default)
			)
			(layer "F.Fab")
		)
		(fp_line
			(start -0.12065 0.2794)
			(end -0.12065 0.3048)
			(stroke
				(width 0.1)
				(type default)
			)
			(layer "F.Fab")
		)
		(fp_line
			(start 0.67945 0.3048)
			(end 0.120396 0.3048)
			(stroke
				(width 0.1)
				(type default)
			)
			(layer "F.Fab")
		)
		(fp_line
			(start 0.120396 0.3048)
			(end 0.120396 0.2794)
			(stroke
				(width 0.1)
				(type default)
			)
			(layer "F.Fab")
		)
		(fp_line
			(start -0.12065 0.3048)
			(end -0.67945 0.3048)
			(stroke
				(width 0.1)
				(type default)
			)
			(layer "F.Fab")
		)
		(fp_line
			(start -0.67945 0.3048)
			(end -0.67945 -0.305054)
			(stroke
				(width 0.1)
				(type default)
			)
			(layer "F.Fab")
		)
		(pad "1" smd circle
			(at -0.40005 0 90)
			(size 0 0)
			(layers "F.Cu" "F.Mask" "F.Paste")
			(net "GND")
		)
		(pad "2" smd circle
			(at 0.40005 0 90)
			(size 0 0)
			(layers "F.Cu" "F.Mask" "F.Paste")
			(net "INA230_5_A0")
		)
	)
	(footprint ""
		(layer "F.Cu")
		(at 106.476038 -41.012364)
		(property "Reference" "R3187"
			(at 0 0 0)
			(layer "F.SilkS")
			(hide yes)
			(effects
				(font
					(size 1.27 1.27)
				)
			)
		)
		(property "Value" ""
			(at 0 0 0)
			(layer "F.Fab")
			(effects
				(font
					(size 1.27 1.27)
				)
			)
		)
		(duplicate_pad_numbers_are_jumpers no)
		(fp_line
			(start -0.7874 -0.4064)
			(end 0.7874 -0.4064)
			(stroke
				(width 0.1524)
				(type default)
			)
			(layer "F.SilkS")
		)
		(fp_line
			(start -0.7874 0.4064)
			(end -0.7874 -0.4064)
			(stroke
				(width 0.1524)
				(type default)
			)
			(layer "F.SilkS")
		)
		(fp_line
			(start 0.7874 -0.4064)
			(end 0.7874 0.4064)
			(stroke
				(width 0.1524)
				(type default)
			)
			(layer "F.SilkS")
		)
		(fp_line
			(start 0.7874 0.4064)
			(end -0.7874 0.4064)
			(stroke
				(width 0.1524)
				(type default)
			)
			(layer "F.SilkS")
		)
		(fp_line
			(start -0.67945 -0.305054)
			(end -0.12065 -0.305054)
			(stroke
				(width 0.1)
				(type default)
			)
			(layer "F.Fab")
		)
		(fp_line
			(start -0.67945 0.3048)
			(end -0.67945 -0.305054)
			(stroke
				(width 0.1)
				(type default)
			)
			(layer "F.Fab")
		)
		(fp_line
			(start -0.12065 -0.305054)
			(end -0.12065 -0.2794)
			(stroke
				(width 0.1)
				(type default)
			)
			(layer "F.Fab")
		)
		(fp_line
			(start -0.12065 -0.2794)
			(end 0.12065 -0.2794)
			(stroke
				(width 0.1)
				(type default)
			)
			(layer "F.Fab")
		)
		(fp_line
			(start -0.12065 0.2794)
			(end -0.12065 0.3048)
			(stroke
				(width 0.1)
				(type default)
			)
			(layer "F.Fab")
		)
		(fp_line
			(start -0.12065 0.3048)
			(end -0.67945 0.3048)
			(stroke
				(width 0.1)
				(type default)
			)
			(layer "F.Fab")
		)
		(fp_line
			(start 0.120396 0.2794)
			(end -0.12065 0.2794)
			(stroke
				(width 0.1)
				(type default)
			)
			(layer "F.Fab")
		)
		(fp_line
			(start 0.120396 0.3048)
			(end 0.120396 0.2794)
			(stroke
				(width 0.1)
				(type default)
			)
			(layer "F.Fab")
		)
		(fp_line
			(start 0.12065 -0.3048)
			(end 0.67945 -0.3048)
			(stroke
				(width 0.1)
				(type default)
			)
			(layer "F.Fab")
		)
		(fp_line
			(start 0.12065 -0.2794)
			(end 0.12065 -0.3048)
			(stroke
				(width 0.1)
				(type default)
			)
			(layer "F.Fab")
		)
		(fp_line
			(start 0.67945 -0.3048)
			(end 0.67945 0.3048)
			(stroke
				(width 0.1)
				(type default)
			)
			(layer "F.Fab")
		)
		(fp_line
			(start 0.67945 0.3048)
			(end 0.120396 0.3048)
			(stroke
				(width 0.1)
				(type default)
			)
			(layer "F.Fab")
		)
		(pad "1" smd circle
			(at -0.40005 0)
			(size 0 0)
			(layers "F.Cu" "F.Mask" "F.Paste")
			(net "RST_OCP_V3_2_BUF_N")
		)
		(pad "2" smd circle
			(at 0.40005 0)
			(size 0 0)
			(layers "F.Cu" "F.Mask" "F.Paste")
			(net "RST_PERST1_OCP_V3_2_N")
		)
	)
	(footprint ""
		(layer "F.Cu")
		(at 213.06155 -22.974554 180)
		(property "Reference" "R1140"
			(at 0 0 180)
			(layer "F.SilkS")
			(hide yes)
			(effects
				(font
					(size 1.27 1.27)
				)
			)
		)
		(property "Value" ""
			(at 0 0 180)
			(layer "F.Fab")
			(effects
				(font
					(size 1.27 1.27)
				)
			)
		)
		(duplicate_pad_numbers_are_jumpers no)
		(fp_line
			(start 0.7874 0.4064)
			(end -0.7874 0.4064)
			(stroke
				(width 0.1524)
				(type default)
			)
			(layer "F.SilkS")
		)
		(fp_line
			(start 0.7874 -0.4064)
			(end 0.7874 0.4064)
			(stroke
				(width 0.1524)
				(type default)
			)
			(layer "F.SilkS")
		)
		(fp_line
			(start -0.7874 0.4064)
			(end -0.7874 -0.4064)
			(stroke
				(width 0.1524)
				(type default)
			)
			(layer "F.SilkS")
		)
		(fp_line
			(start -0.7874 -0.4064)
			(end 0.7874 -0.4064)
			(stroke
				(width 0.1524)
				(type default)
			)
			(layer "F.SilkS")
		)
		(fp_line
			(start 0.67945 0.3048)
			(end 0.120396 0.3048)
			(stroke
				(width 0.1)
				(type default)
			)
			(layer "F.Fab")
		)
		(fp_line
			(start 0.67945 -0.3048)
			(end 0.67945 0.3048)
			(stroke
				(width 0.1)
				(type default)
			)
			(layer "F.Fab")
		)
		(fp_line
			(start 0.12065 -0.2794)
			(end 0.12065 -0.3048)
			(stroke
				(width 0.1)
				(type default)
			)
			(layer "F.Fab")
		)
		(fp_line
			(start 0.12065 -0.3048)
			(end 0.67945 -0.3048)
			(stroke
				(width 0.1)
				(type default)
			)
			(layer "F.Fab")
		)
		(fp_line
			(start 0.120396 0.3048)
			(end 0.120396 0.2794)
			(stroke
				(width 0.1)
				(type default)
			)
			(layer "F.Fab")
		)
		(fp_line
			(start 0.120396 0.2794)
			(end -0.12065 0.2794)
			(stroke
				(width 0.1)
				(type default)
			)
			(layer "F.Fab")
		)
		(fp_line
			(start -0.12065 0.3048)
			(end -0.67945 0.3048)
			(stroke
				(width 0.1)
				(type default)
			)
			(layer "F.Fab")
		)
		(fp_line
			(start -0.12065 0.2794)
			(end -0.12065 0.3048)
			(stroke
				(width 0.1)
				(type default)
			)
			(layer "F.Fab")
		)
		(fp_line
			(start -0.12065 -0.2794)
			(end 0.12065 -0.2794)
			(stroke
				(width 0.1)
				(type default)
			)
			(layer "F.Fab")
		)
		(fp_line
			(start -0.12065 -0.305054)
			(end -0.12065 -0.2794)
			(stroke
				(width 0.1)
				(type default)
			)
			(layer "F.Fab")
		)
		(fp_line
			(start -0.67945 0.3048)
			(end -0.67945 -0.305054)
			(stroke
				(width 0.1)
				(type default)
			)
			(layer "F.Fab")
		)
		(fp_line
			(start -0.67945 -0.305054)
			(end -0.12065 -0.305054)
			(stroke
				(width 0.1)
				(type default)
			)
			(layer "F.Fab")
		)
		(pad "1" smd circle
			(at -0.40005 0 180)
			(size 0 0)
			(layers "F.Cu" "F.Mask" "F.Paste")
			(net "CLK_50M_BMC_MAC_R")
		)
		(pad "2" smd circle
			(at 0.40005 0 180)
			(size 0 0)
			(layers "F.Cu" "F.Mask" "F.Paste")
			(net "CLK_50M_RMII_BMC_OCP")
		)
	)
	(footprint ""
		(layer "F.Cu")
		(at 295.86682 -421.41521 90)
		(property "Reference" "R4156"
			(at 0 0 90)
			(layer "F.SilkS")
			(hide yes)
			(effects
				(font
					(size 1.27 1.27)
				)
			)
		)
		(property "Value" ""
			(at 0 0 90)
			(layer "F.Fab")
			(effects
				(font
					(size 1.27 1.27)
				)
			)
		)
		(duplicate_pad_numbers_are_jumpers no)
		(fp_line
			(start 0.7874 -0.4064)
			(end 0.7874 0.4064)
			(stroke
				(width 0.1524)
				(type default)
			)
			(layer "F.SilkS")
		)
		(fp_line
			(start -0.7874 -0.4064)
			(end 0.7874 -0.4064)
			(stroke
				(width 0.1524)
				(type default)
			)
			(layer "F.SilkS")
		)
		(fp_line
			(start 0.7874 0.4064)
			(end -0.7874 0.4064)
			(stroke
				(width 0.1524)
				(type default)
			)
			(layer "F.SilkS")
		)
		(fp_line
			(start -0.7874 0.4064)
			(end -0.7874 -0.4064)
			(stroke
				(width 0.1524)
				(type default)
			)
			(layer "F.SilkS")
		)
		(fp_line
			(start -0.12065 -0.305054)
			(end -0.12065 -0.2794)
			(stroke
				(width 0.1)
				(type default)
			)
			(layer "F.Fab")
		)
		(fp_line
			(start -0.67945 -0.305054)
			(end -0.12065 -0.305054)
			(stroke
				(width 0.1)
				(type default)
			)
			(layer "F.Fab")
		)
		(fp_line
			(start 0.67945 -0.3048)
			(end 0.67945 0.3048)
			(stroke
				(width 0.1)
				(type default)
			)
			(layer "F.Fab")
		)
		(fp_line
			(start 0.12065 -0.3048)
			(end 0.67945 -0.3048)
			(stroke
				(width 0.1)
				(type default)
			)
			(layer "F.Fab")
		)
		(fp_line
			(start 0.12065 -0.2794)
			(end 0.12065 -0.3048)
			(stroke
				(width 0.1)
				(type default)
			)
			(layer "F.Fab")
		)
		(fp_line
			(start -0.12065 -0.2794)
			(end 0.12065 -0.2794)
			(stroke
				(width 0.1)
				(type default)
			)
			(layer "F.Fab")
		)
		(fp_line
			(start 0.120396 0.2794)
			(end -0.12065 0.2794)
			(stroke
				(width 0.1)
				(type default)
			)
			(layer "F.Fab")
		)
		(fp_line
			(start -0.12065 0.2794)
			(end -0.12065 0.3048)
			(stroke
				(width 0.1)
				(type default)
			)
			(layer "F.Fab")
		)
		(fp_line
			(start 0.67945 0.3048)
			(end 0.120396 0.3048)
			(stroke
				(width 0.1)
				(type default)
			)
			(layer "F.Fab")
		)
		(fp_line
			(start 0.120396 0.3048)
			(end 0.120396 0.2794)
			(stroke
				(width 0.1)
				(type default)
			)
			(layer "F.Fab")
		)
		(fp_line
			(start -0.12065 0.3048)
			(end -0.67945 0.3048)
			(stroke
				(width 0.1)
				(type default)
			)
			(layer "F.Fab")
		)
		(fp_line
			(start -0.67945 0.3048)
			(end -0.67945 -0.305054)
			(stroke
				(width 0.1)
				(type default)
			)
			(layer "F.Fab")
		)
		(pad "1" smd circle
			(at -0.40005 0 90)
			(size 0 0)
			(layers "F.Cu" "F.Mask" "F.Paste")
			(net "P3V3_AUX")
		)
		(pad "2" smd circle
			(at 0.40005 0 90)
			(size 0 0)
			(layers "F.Cu" "F.Mask" "F.Paste")
			(net "PRSNT_CABLE_GPU_A1_ISO_N")
		)
	)
	(footprint ""
		(layer "F.Cu")
		(at 366.454182 -423.03573)
		(property "Reference" "R4215"
			(at 0 0 0)
			(layer "F.SilkS")
			(hide yes)
			(effects
				(font
					(size 1.27 1.27)
				)
			)
		)
		(property "Value" ""
			(at 0 0 0)
			(layer "F.Fab")
			(effects
				(font
					(size 1.27 1.27)
				)
			)
		)
		(duplicate_pad_numbers_are_jumpers no)
		(fp_line
			(start -0.7874 -0.4064)
			(end 0.7874 -0.4064)
			(stroke
				(width 0.1524)
				(type default)
			)
			(layer "F.SilkS")
		)
		(fp_line
			(start -0.7874 0.4064)
			(end -0.7874 -0.4064)
			(stroke
				(width 0.1524)
				(type default)
			)
			(layer "F.SilkS")
		)
		(fp_line
			(start 0.7874 -0.4064)
			(end 0.7874 0.4064)
			(stroke
				(width 0.1524)
				(type default)
			)
			(layer "F.SilkS")
		)
		(fp_line
			(start 0.7874 0.4064)
			(end -0.7874 0.4064)
			(stroke
				(width 0.1524)
				(type default)
			)
			(layer "F.SilkS")
		)
		(fp_line
			(start -0.67945 -0.305054)
			(end -0.12065 -0.305054)
			(stroke
				(width 0.1)
				(type default)
			)
			(layer "F.Fab")
		)
		(fp_line
			(start -0.67945 0.3048)
			(end -0.67945 -0.305054)
			(stroke
				(width 0.1)
				(type default)
			)
			(layer "F.Fab")
		)
		(fp_line
			(start -0.12065 -0.305054)
			(end -0.12065 -0.2794)
			(stroke
				(width 0.1)
				(type default)
			)
			(layer "F.Fab")
		)
		(fp_line
			(start -0.12065 -0.2794)
			(end 0.12065 -0.2794)
			(stroke
				(width 0.1)
				(type default)
			)
			(layer "F.Fab")
		)
		(fp_line
			(start -0.12065 0.2794)
			(end -0.12065 0.3048)
			(stroke
				(width 0.1)
				(type default)
			)
			(layer "F.Fab")
		)
		(fp_line
			(start -0.12065 0.3048)
			(end -0.67945 0.3048)
			(stroke
				(width 0.1)
				(type default)
			)
			(layer "F.Fab")
		)
		(fp_line
			(start 0.120396 0.2794)
			(end -0.12065 0.2794)
			(stroke
				(width 0.1)
				(type default)
			)
			(layer "F.Fab")
		)
		(fp_line
			(start 0.120396 0.3048)
			(end 0.120396 0.2794)
			(stroke
				(width 0.1)
				(type default)
			)
			(layer "F.Fab")
		)
		(fp_line
			(start 0.12065 -0.3048)
			(end 0.67945 -0.3048)
			(stroke
				(width 0.1)
				(type default)
			)
			(layer "F.Fab")
		)
		(fp_line
			(start 0.12065 -0.2794)
			(end 0.12065 -0.3048)
			(stroke
				(width 0.1)
				(type default)
			)
			(layer "F.Fab")
		)
		(fp_line
			(start 0.67945 -0.3048)
			(end 0.67945 0.3048)
			(stroke
				(width 0.1)
				(type default)
			)
			(layer "F.Fab")
		)
		(fp_line
			(start 0.67945 0.3048)
			(end 0.120396 0.3048)
			(stroke
				(width 0.1)
				(type default)
			)
			(layer "F.Fab")
		)
		(pad "1" smd circle
			(at -0.40005 0)
			(size 0 0)
			(layers "F.Cu" "F.Mask" "F.Paste")
			(net "FM_THERMAL_ALERT_N")
		)
		(pad "2" smd circle
			(at 0.40005 0)
			(size 0 0)
			(layers "F.Cu" "F.Mask" "F.Paste")
			(net "FM_G751_0_ALERT_N")
		)
	)
)
